# S9S_MB_2U (Grand Teton) — schematic netlist excerpt (pin names and nets, part order shuffled) for the footprints in the layout excerpt that follows; sources: Cadence DE-HDL packaged netlist, KiCad conversion of 03242023_DA0F0TMBIJ0_F0T_Motherboard_J_brd_V01_OCP.brd

C1318  Q_CAP  1UF 25V 10% EMPTY  pkg C0402  page 244 : A = PWRGD_DSW_PWROK_R1 ; B = GND
C2454  Q_CAP  1000PF 50V 5% EMPTY  pkg 0402  page 296 : A = PWRGD_PVCCD_HV_CPU1_R ; B = GND

(kicad_pcb
	(version 20260206)
	(generator "pcbnew")
	(generator_version "10.0")
	(general
		(thickness 1.6)
		(legacy_teardrops no)
	)
	(paper "A4")
	(title_block
		(title "03242023_DA0F0TMBIJ0_F0T_Motherboard_J_brd_V01_OCP.brd")
		(comment 1 "Grand Teton / footprints 1147-1148 of 6105")
	)
	(layers
		(0 "F.Cu" signal "TOP")
		(4 "In1.Cu" signal "GND")
		(6 "In2.Cu" signal "IN1")
		(8 "In3.Cu" signal "GND1")
		(10 "In4.Cu" signal "IN2")
		(12 "In5.Cu" signal "GND2")
		(14 "In6.Cu" signal "IN3")
		(16 "In7.Cu" signal "GND3")
		(18 "In8.Cu" signal "VCC")
		(20 "In9.Cu" signal "VCC1")
		(22 "In10.Cu" signal "GND4")
		(24 "In11.Cu" signal "IN4")
		(26 "In12.Cu" signal "GND5")
		(28 "In13.Cu" signal "IN5")
		(30 "In14.Cu" signal "GND6")
		(32 "In15.Cu" signal "IN6")
		(34 "In16.Cu" signal "GND7")
		(2 "B.Cu" signal "BOTTOM")
		(9 "F.Adhes" user "F.Adhesive")
		(11 "B.Adhes" user "B.Adhesive")
		(13 "F.Paste" user "Package Geometry/Pastemask Top")
		(15 "B.Paste" user "Package Geometry/Pastemask Bottom")
		(5 "F.SilkS" user "Ref Des/Silkscreen Top")
		(7 "B.SilkS" user "Ref Des/Silkscreen Bottom")
		(1 "F.Mask" user "Board Geometry/Soldermask Top")
		(3 "B.Mask" user "Board Geometry/Soldermask Bottom")
		(17 "Dwgs.User" user "User.Drawings")
		(19 "Cmts.User" user "User.Comments")
		(21 "Eco1.User" user "User.Eco1")
		(23 "Eco2.User" user "User.Eco2")
		(25 "Edge.Cuts" user "Board Geometry/Outline")
		(27 "Margin" user)
		(31 "F.CrtYd" user "Package Geometry/Place Bound Top")
		(29 "B.CrtYd" user "Package Geometry/Place Bound Bottom")
		(35 "F.Fab" user "Ref Des/Assembly Top")
		(33 "B.Fab" user "Ref Des/Assembly Bottom")
	)
	(footprint ""
		(layer "F.Cu")
		(at 22.64156 -169.604436 180)
		(property "Reference" "C2454"
			(at 0 0 180)
			(layer "F.SilkS")
			(hide yes)
			(effects
				(font
					(size 1.27 1.27)
				)
			)
		)
		(property "Value" ""
			(at 0 0 180)
			(layer "F.Fab")
			(effects
				(font
					(size 1.27 1.27)
				)
			)
		)
		(duplicate_pad_numbers_are_jumpers no)
		(fp_line
			(start 0.7874 0.4064)
			(end -0.7874 0.4064)
			(stroke
				(width 0.1524)
				(type default)
			)
			(layer "F.SilkS")
		)
		(fp_line
			(start 0.7874 -0.4064)
			(end 0.7874 0.4064)
			(stroke
				(width 0.1524)
				(type default)
			)
			(layer "F.SilkS")
		)
		(fp_line
			(start -0.7874 0.4064)
			(end -0.7874 -0.4064)
			(stroke
				(width 0.1524)
				(type default)
			)
			(layer "F.SilkS")
		)
		(fp_line
			(start -0.7874 -0.4064)
			(end 0.7874 -0.4064)
			(stroke
				(width 0.1524)
				(type default)
			)
			(layer "F.SilkS")
		)
		(fp_line
			(start 0.67945 0.3048)
			(end 0.120396 0.3048)
			(stroke
				(width 0.1)
				(type default)
			)
			(layer "F.Fab")
		)
		(fp_line
			(start 0.67945 -0.3048)
			(end 0.67945 0.3048)
			(stroke
				(width 0.1)
				(type default)
			)
			(layer "F.Fab")
		)
		(fp_line
			(start 0.12065 -0.2794)
			(end 0.12065 -0.3048)
			(stroke
				(width 0.1)
				(type default)
			)
			(layer "F.Fab")
		)
		(fp_line
			(start 0.12065 -0.3048)
			(end 0.67945 -0.3048)
			(stroke
				(width 0.1)
				(type default)
			)
			(layer "F.Fab")
		)
		(fp_line
			(start 0.120396 0.3048)
			(end 0.120396 0.2794)
			(stroke
				(width 0.1)
				(type default)
			)
			(layer "F.Fab")
		)
		(fp_line
			(start 0.120396 0.2794)
			(end -0.12065 0.2794)
			(stroke
				(width 0.1)
				(type default)
			)
			(layer "F.Fab")
		)
		(fp_line
			(start -0.12065 0.3048)
			(end -0.67945 0.3048)
			(stroke
				(width 0.1)
				(type default)
			)
			(layer "F.Fab")
		)
		(fp_line
			(start -0.12065 0.2794)
			(end -0.12065 0.3048)
			(stroke
				(width 0.1)
				(type default)
			)
			(layer "F.Fab")
		)
		(fp_line
			(start -0.12065 -0.2794)
			(end 0.12065 -0.2794)
			(stroke
				(width 0.1)
				(type default)
			)
			(layer "F.Fab")
		)
		(fp_line
			(start -0.12065 -0.305054)
			(end -0.12065 -0.2794)
			(stroke
				(width 0.1)
				(type default)
			)
			(layer "F.Fab")
		)
		(fp_line
			(start -0.67945 0.3048)
			(end -0.67945 -0.305054)
			(stroke
				(width 0.1)
				(type default)
			)
			(layer "F.Fab")
		)
		(fp_line
			(start -0.67945 -0.305054)
			(end -0.12065 -0.305054)
			(stroke
				(width 0.1)
				(type default)
			)
			(layer "F.Fab")
		)
		(pad "1" smd circle
			(at -0.40005 0 180)
			(size 0 0)
			(layers "F.Cu" "F.Mask" "F.Paste")
			(net "PWRGD_PVCCD_HV_CPU1_R")
		)
		(pad "2" smd circle
			(at 0.40005 0 180)
			(size 0 0)
			(layers "F.Cu" "F.Mask" "F.Paste")
			(net "GND")
		)
	)
	(footprint ""
		(layer "F.Cu")
		(at 218.08948 -127.803148)
		(property "Reference" "C1318"
			(at 0 0 0)
			(layer "F.SilkS")
			(hide yes)
			(effects
				(font
					(size 1.27 1.27)
				)
			)
		)
		(property "Value" ""
			(at 0 0 0)
			(layer "F.Fab")
			(effects
				(font
					(size 1.27 1.27)
				)
			)
		)
		(duplicate_pad_numbers_are_jumpers no)
		(fp_line
			(start -0.7874 -0.4064)
			(end 0.7874 -0.4064)
			(stroke
				(width 0.1524)
				(type default)
			)
			(layer "F.SilkS")
		)
		(fp_line
			(start -0.7874 0.4064)
			(end -0.7874 -0.4064)
			(stroke
				(width 0.1524)
				(type default)
			)
			(layer "F.SilkS")
		)
		(fp_line
			(start 0.7874 -0.4064)
			(end 0.7874 0.4064)
			(stroke
				(width 0.1524)
				(type default)
			)
			(layer "F.SilkS")
		)
		(fp_line
			(start 0.7874 0.4064)
			(end -0.7874 0.4064)
			(stroke
				(width 0.1524)
				(type default)
			)
			(layer "F.SilkS")
		)
		(fp_line
			(start -0.67945 -0.305054)
			(end -0.12065 -0.305054)
			(stroke
				(width 0.1)
				(type default)
			)
			(layer "F.Fab")
		)
		(fp_line
			(start -0.67945 0.3048)
			(end -0.67945 -0.305054)
			(stroke
				(width 0.1)
				(type default)
			)
			(layer "F.Fab")
		)
		(fp_line
			(start -0.12065 -0.305054)
			(end -0.12065 -0.2794)
			(stroke
				(width 0.1)
				(type default)
			)
			(layer "F.Fab")
		)
		(fp_line
			(start -0.12065 -0.2794)
			(end 0.12065 -0.2794)
			(stroke
				(width 0.1)
				(type default)
			)
			(layer "F.Fab")
		)
		(fp_line
			(start -0.12065 0.2794)
			(end -0.12065 0.3048)
			(stroke
				(width 0.1)
				(type default)
			)
			(layer "F.Fab")
		)
		(fp_line
			(start -0.12065 0.3048)
			(end -0.67945 0.3048)
			(stroke
				(width 0.1)
				(type default)
			)
			(layer "F.Fab")
		)
		(fp_line
			(start 0.120396 0.2794)
			(end -0.12065 0.2794)
			(stroke
				(width 0.1)
				(type default)
			)
			(layer "F.Fab")
		)
		(fp_line
			(start 0.120396 0.3048)
			(end 0.120396 0.2794)
			(stroke
				(width 0.1)
				(type default)
			)
			(layer "F.Fab")
		)
		(fp_line
			(start 0.12065 -0.3048)
			(end 0.67945 -0.3048)
			(stroke
				(width 0.1)
				(type default)
			)
			(layer "F.Fab")
		)
		(fp_line
			(start 0.12065 -0.2794)
			(end 0.12065 -0.3048)
			(stroke
				(width 0.1)
				(type default)
			)
			(layer "F.Fab")
		)
		(fp_line
			(start 0.67945 -0.3048)
			(end 0.67945 0.3048)
			(stroke
				(width 0.1)
				(type default)
			)
			(layer "F.Fab")
		)
		(fp_line
			(start 0.67945 0.3048)
			(end 0.120396 0.3048)
			(stroke
				(width 0.1)
				(type default)
			)
			(layer "F.Fab")
		)
		(pad "1" smd circle
			(at -0.40005 0)
			(size 0 0)
			(layers "F.Cu" "F.Mask" "F.Paste")
			(net "PWRGD_DSW_PWROK_R1")
		)
		(pad "2" smd circle
			(at 0.40005 0)
			(size 0 0)
			(layers "F.Cu" "F.Mask" "F.Paste")
			(net "GND")
		)
	)
)
